(kicad_pcb
	(version 20260206)
	(generator "pcbnew")
	(generator_version "10.0")
	(general
		(thickness 1.6)
		(legacy_teardrops no)
	)
	(paper "A4")
	(title_block
		(title "04192023_DAF0TMB3IC0_F0TG_MB_C_brd_V02_OCP.brd")
		(comment 1 "Grand Teton / footprints 6288-6294 of 8354")
	)
	(layers
		(0 "F.Cu" signal "TOP")
		(4 "In1.Cu" signal "GND")
		(6 "In2.Cu" signal "IN1")
		(8 "In3.Cu" signal "GND1")
		(10 "In4.Cu" signal "IN2")
		(12 "In5.Cu" signal "GND2")
		(14 "In6.Cu" signal "IN3")
		(16 "In7.Cu" signal "GND3")
		(18 "In8.Cu" signal "VCC")
		(20 "In9.Cu" signal "VCC1")
		(22 "In10.Cu" signal "GND4")
		(24 "In11.Cu" signal "IN4")
		(26 "In12.Cu" signal "GND5")
		(28 "In13.Cu" signal "IN5")
		(30 "In14.Cu" signal "GND6")
		(32 "In15.Cu" signal "IN6")
		(34 "In16.Cu" signal "GND7")
		(2 "B.Cu" signal "BOTTOM")
		(9 "F.Adhes" user "F.Adhesive")
		(11 "B.Adhes" user "B.Adhesive")
		(13 "F.Paste" user "Package Geometry/Pastemask Top")
		(15 "B.Paste" user "Package Geometry/Pastemask Bottom")
		(5 "F.SilkS" user "Ref Des/Silkscreen Top")
		(7 "B.SilkS" user "Ref Des/Silkscreen Bottom")
		(1 "F.Mask" user "Board Geometry/Soldermask Top")
		(3 "B.Mask" user "Board Geometry/Soldermask Bottom")
		(17 "Dwgs.User" user "User.Drawings")
		(19 "Cmts.User" user "User.Comments")
		(21 "Eco1.User" user "User.Eco1")
		(23 "Eco2.User" user "User.Eco2")
		(25 "Edge.Cuts" user "Board Geometry/Outline")
		(27 "Margin" user)
		(31 "F.CrtYd" user "Package Geometry/Place Bound Top")
		(29 "B.CrtYd" user "Package Geometry/Place Bound Bottom")
		(35 "F.Fab" user "Ref Des/Assembly Top")
		(33 "B.Fab" user "Ref Des/Assembly Bottom")
	)
	(footprint ""
		(layer "B.Cu")
		(at 498.311424 -306.87518 90)
		(property "Reference" "X9025"
			(at 4.62026 -1.55829 90)
			(unlocked yes)
			(layer "B.SilkS")
			(effects
				(font
					(size 0.7874 0.5842)
					(thickness 0.1524)
				)
				(justify left mirror)
			)
		)
		(property "Value" ""
			(at 0 0 90)
			(layer "B.Fab")
			(effects
				(font
					(size 1.27 1.27)
				)
				(justify mirror)
			)
		)
		(property "User Part Number" "N_A"
			(at -1.30175 1.27 0)
			(unlocked yes)
			(layer "Cmts.User")
			(hide yes)
			(effects
				(font
					(size 0.635 0.4064)
					(thickness 0.1524)
				)
				(justify mirror)
			)
		)
		(property "Device Type" "TP_TDR_4P_FTS_TH-TP_TDR_4P_DIP,EMPTY,TP15"
			(at -1.30175 1.27 0)
			(unlocked yes)
			(layer "B.Fab")
			(hide yes)
			(effects
				(font
					(size 0.635 0.4064)
					(thickness 0.1524)
				)
				(justify mirror)
			)
		)
		(duplicate_pad_numbers_are_jumpers no)
		(fp_line
			(start 0 -1.27)
			(end 0 -0.635)
			(stroke
				(width 0.1524)
				(type default)
			)
			(layer "B.SilkS")
		)
		(fp_line
			(start -2.54 -1.27)
			(end 0 -1.27)
			(stroke
				(width 0.1524)
				(type default)
			)
			(layer "B.SilkS")
		)
		(fp_line
			(start -2.54 -1.1303)
			(end -2.54 -1.27)
			(stroke
				(width 0.1524)
				(type default)
			)
			(layer "B.SilkS")
		)
		(fp_line
			(start 0 0.635)
			(end 0 1.905)
			(stroke
				(width 0.1524)
				(type default)
			)
			(layer "B.SilkS")
		)
		(fp_line
			(start -2.54 1.4097)
			(end -2.54 1.1303)
			(stroke
				(width 0.1524)
				(type default)
			)
			(layer "B.SilkS")
		)
		(fp_line
			(start 0 3.175)
			(end 0 3.81)
			(stroke
				(width 0.1524)
				(type default)
			)
			(layer "B.SilkS")
		)
		(fp_line
			(start 0 3.81)
			(end -2.54 3.81)
			(stroke
				(width 0.1524)
				(type default)
			)
			(layer "B.SilkS")
		)
		(fp_line
			(start -2.54 3.81)
			(end -2.54 3.6703)
			(stroke
				(width 0.1524)
				(type default)
			)
			(layer "B.SilkS")
		)
		(fp_poly
			(pts
				(xy 0.761746 0) (xy 2.285746 -0.762) (xy 2.285746 0.762)
			)
			(stroke
				(width 0)
				(type default)
			)
			(fill yes)
			(layer "B.SilkS")
		)
		(fp_line
			(start 0 -1.27)
			(end 0 3.81)
			(stroke
				(width 0.1)
				(type default)
			)
			(layer "B.Fab")
		)
		(fp_line
			(start -2.54 -1.27)
			(end 0 -1.27)
			(stroke
				(width 0.1)
				(type default)
			)
			(layer "B.Fab")
		)
		(fp_line
			(start 0 3.81)
			(end -2.54 3.81)
			(stroke
				(width 0.1)
				(type default)
			)
			(layer "B.Fab")
		)
		(fp_line
			(start -2.54 3.81)
			(end -2.54 -1.27)
			(stroke
				(width 0.1)
				(type default)
			)
			(layer "B.Fab")
		)
		(fp_poly
			(pts
				(xy 0.761746 0) (xy 2.285746 -0.762) (xy 2.285746 0.762)
			)
			(stroke
				(width 0)
				(type default)
			)
			(fill yes)
			(layer "B.Fab")
		)
		(pad "1" thru_hole circle
			(at 0 0 270)
			(size 1.0033 1.0033)
			(drill 0.249936)
			(layers "*.Cu" "*.Mask")
			(remove_unused_layers no)
			(net "TDR_DIFF_85_NECK_IN5_DP")
			(clearance 0.10795)
			(padstack
				(mode front_inner_back)
				(layer "Inner"
					(shape circle)
					(size 0.8001 0.8001)
					(clearance 0.1524)
				)
				(layer "B.Cu"
					(shape circle)
					(size 1.0033 1.0033)
					(thermal_gap 0.10795)
					(clearance 0.10795)
				)
			)
		)
		(pad "2" thru_hole circle
			(at -2.54 0 270)
			(size 1.9939 1.9939)
			(drill 0.249936)
			(layers "*.Cu" "*.Mask")
			(remove_unused_layers no)
			(net "T1_GND")
			(clearance 0.10795)
			(padstack
				(mode front_inner_back)
				(layer "Inner"
					(shape circle)
					(size 0.8001 0.8001)
					(clearance 0.1524)
				)
				(layer "B.Cu"
					(shape circle)
					(size 1.9939 1.9939)
					(thermal_gap 0.10795)
					(clearance 0.10795)
				)
			)
		)
		(pad "3" thru_hole circle
			(at -2.54 2.54 270)
			(size 1.9939 1.9939)
			(drill 0.249936)
			(layers "*.Cu" "*.Mask")
			(remove_unused_layers no)
			(net "T1_GND")
			(clearance 0.10795)
			(padstack
				(mode front_inner_back)
				(layer "Inner"
					(shape circle)
					(size 0.8001 0.8001)
					(clearance 0.1524)
				)
				(layer "B.Cu"
					(shape circle)
					(size 1.9939 1.9939)
					(thermal_gap 0.10795)
					(clearance 0.10795)
				)
			)
		)
		(pad "4" thru_hole circle
			(at 0 2.54 270)
			(size 1.0033 1.0033)
			(drill 0.249936)
			(layers "*.Cu" "*.Mask")
			(remove_unused_layers no)
			(net "TDR_DIFF_85_NECK_IN5_DN")
			(clearance 0.10795)
			(padstack
				(mode front_inner_back)
				(layer "Inner"
					(shape circle)
					(size 0.8001 0.8001)
					(clearance 0.1524)
				)
				(layer "B.Cu"
					(shape circle)
					(size 1.0033 1.0033)
					(thermal_gap 0.10795)
					(clearance 0.10795)
				)
			)
		)
	)
	(footprint ""
		(layer "B.Cu")
		(at 101.92512 -191.278002 90)
		(property "Reference" "PC304_3"
			(at 0 0 90)
			(layer "B.SilkS")
			(hide yes)
			(effects
				(font
					(size 1.27 1.27)
				)
				(justify mirror)
			)
		)
		(property "Value" ""
			(at 0 0 90)
			(layer "B.Fab")
			(effects
				(font
					(size 1.27 1.27)
				)
				(justify mirror)
			)
		)
		(duplicate_pad_numbers_are_jumpers no)
		(fp_line
			(start 1.524 -0.762)
			(end -1.524 -0.762)
			(stroke
				(width 0.1524)
				(type default)
			)
			(layer "B.SilkS")
		)
		(fp_line
			(start -1.524 -0.762)
			(end -1.524 0.762)
			(stroke
				(width 0.1524)
				(type default)
			)
			(layer "B.SilkS")
		)
		(fp_line
			(start 1.524 0.762)
			(end 1.524 -0.762)
			(stroke
				(width 0.1524)
				(type default)
			)
			(layer "B.SilkS")
		)
		(fp_line
			(start -1.524 0.762)
			(end 1.524 0.762)
			(stroke
				(width 0.1524)
				(type default)
			)
			(layer "B.SilkS")
		)
		(fp_line
			(start 1.1049 -0.724916)
			(end 1.1049 0.724916)
			(stroke
				(width 0.1)
				(type default)
			)
			(layer "B.Fab")
		)
		(fp_line
			(start -1.1049 -0.724916)
			(end 1.1049 -0.724916)
			(stroke
				(width 0.1)
				(type default)
			)
			(layer "B.Fab")
		)
		(fp_line
			(start 1.1049 0.724916)
			(end -1.1049 0.724916)
			(stroke
				(width 0.1)
				(type default)
			)
			(layer "B.Fab")
		)
		(fp_line
			(start -1.1049 0.724916)
			(end -1.1049 -0.724916)
			(stroke
				(width 0.1)
				(type default)
			)
			(layer "B.Fab")
		)
		(pad "1" smd rect
			(at 0.889 0 90)
			(size 1.016 1.27)
			(layers "B.Cu" "B.Mask" "B.Paste")
			(net "PVDDCR_CPU0_P1")
		)
		(pad "2" smd rect
			(at -0.889 0 90)
			(size 1.016 1.27)
			(layers "B.Cu" "B.Mask" "B.Paste")
			(net "GND")
		)
	)
	(footprint ""
		(layer "B.Cu")
		(at 216.027 -333.883 -90)
		(property "Reference" "R6718"
			(at 0 0 90)
			(layer "B.SilkS")
			(hide yes)
			(effects
				(font
					(size 1.27 1.27)
				)
				(justify mirror)
			)
		)
		(property "Value" ""
			(at 0 0 90)
			(layer "B.Fab")
			(effects
				(font
					(size 1.27 1.27)
				)
				(justify mirror)
			)
		)
		(duplicate_pad_numbers_are_jumpers no)
		(fp_line
			(start -0.32512 0.175006)
			(end 0.32512 0.175006)
			(stroke
				(width 0.1)
				(type default)
			)
			(layer "B.Fab")
		)
		(fp_line
			(start 0.32512 0.175006)
			(end 0.32512 -0.175006)
			(stroke
				(width 0.1)
				(type default)
			)
			(layer "B.Fab")
		)
		(fp_line
			(start -0.32512 -0.175006)
			(end -0.32512 0.175006)
			(stroke
				(width 0.1)
				(type default)
			)
			(layer "B.Fab")
		)
		(fp_line
			(start 0.32512 -0.175006)
			(end -0.32512 -0.175006)
			(stroke
				(width 0.1)
				(type default)
			)
			(layer "B.Fab")
		)
		(pad "1" smd rect
			(at 0.2667 0 90)
			(size 0.3048 0.381)
			(layers "B.Cu" "B.Mask" "B.Paste")
			(net "P1V8_CPU1_RT_1D")
		)
		(pad "2" smd rect
			(at -0.2667 0 270)
			(size 0.3048 0.381)
			(layers "B.Cu" "B.Mask" "B.Paste")
			(net "SMB_RT_CPU1_P0_R_SDA")
		)
	)
	(footprint ""
		(layer "B.Cu")
		(at 129.305304 -32.638492)
		(property "Reference" "C6082"
			(at 0 0 0)
			(layer "B.SilkS")
			(hide yes)
			(effects
				(font
					(size 1.27 1.27)
				)
				(justify mirror)
			)
		)
		(property "Value" ""
			(at 0 0 0)
			(layer "B.Fab")
			(effects
				(font
					(size 1.27 1.27)
				)
				(justify mirror)
			)
		)
		(duplicate_pad_numbers_are_jumpers no)
		(fp_line
			(start -0.7874 -0.4064)
			(end -0.7874 0.4064)
			(stroke
				(width 0.1524)
				(type default)
			)
			(layer "B.SilkS")
		)
		(fp_line
			(start -0.7874 0.4064)
			(end 0.7874 0.4064)
			(stroke
				(width 0.1524)
				(type default)
			)
			(layer "B.SilkS")
		)
		(fp_line
			(start 0.7874 -0.4064)
			(end -0.7874 -0.4064)
			(stroke
				(width 0.1524)
				(type default)
			)
			(layer "B.SilkS")
		)
		(fp_line
			(start 0.7874 0.4064)
			(end 0.7874 -0.4064)
			(stroke
				(width 0.1524)
				(type default)
			)
			(layer "B.SilkS")
		)
		(fp_line
			(start -0.67945 -0.3048)
			(end -0.67945 0.3048)
			(stroke
				(width 0.1)
				(type default)
			)
			(layer "B.Fab")
		)
		(fp_line
			(start -0.67945 0.3048)
			(end -0.120396 0.3048)
			(stroke
				(width 0.1)
				(type default)
			)
			(layer "B.Fab")
		)
		(fp_line
			(start -0.12065 -0.3048)
			(end -0.67945 -0.3048)
			(stroke
				(width 0.1)
				(type default)
			)
			(layer "B.Fab")
		)
		(fp_line
			(start -0.12065 -0.2794)
			(end -0.12065 -0.3048)
			(stroke
				(width 0.1)
				(type default)
			)
			(layer "B.Fab")
		)
		(fp_line
			(start -0.120396 0.2794)
			(end 0.12065 0.2794)
			(stroke
				(width 0.1)
				(type default)
			)
			(layer "B.Fab")
		)
		(fp_line
			(start -0.120396 0.3048)
			(end -0.120396 0.2794)
			(stroke
				(width 0.1)
				(type default)
			)
			(layer "B.Fab")
		)
		(fp_line
			(start 0.12065 -0.305054)
			(end 0.12065 -0.2794)
			(stroke
				(width 0.1)
				(type default)
			)
			(layer "B.Fab")
		)
		(fp_line
			(start 0.12065 -0.2794)
			(end -0.12065 -0.2794)
			(stroke
				(width 0.1)
				(type default)
			)
			(layer "B.Fab")
		)
		(fp_line
			(start 0.12065 0.2794)
			(end 0.12065 0.3048)
			(stroke
				(width 0.1)
				(type default)
			)
			(layer "B.Fab")
		)
		(fp_line
			(start 0.12065 0.3048)
			(end 0.67945 0.3048)
			(stroke
				(width 0.1)
				(type default)
			)
			(layer "B.Fab")
		)
		(fp_line
			(start 0.67945 -0.305054)
			(end 0.12065 -0.305054)
			(stroke
				(width 0.1)
				(type default)
			)
			(layer "B.Fab")
		)
		(fp_line
			(start 0.67945 0.3048)
			(end 0.67945 -0.305054)
			(stroke
				(width 0.1)
				(type default)
			)
			(layer "B.Fab")
		)
		(pad "1" smd circle
			(at 0.40005 0 180)
			(size 0 0)
			(layers "B.Cu" "B.Mask" "B.Paste")
			(net "P1V2_AUX")
		)
		(pad "2" smd circle
			(at -0.40005 0 180)
			(size 0 0)
			(layers "B.Cu" "B.Mask" "B.Paste")
			(net "GND")
		)
	)
	(footprint ""
		(layer "B.Cu")
		(at 367.233454 -253.43231)
		(property "Reference" "C2143"
			(at 0 0 0)
			(layer "B.SilkS")
			(hide yes)
			(effects
				(font
					(size 1.27 1.27)
				)
				(justify mirror)
			)
		)
		(property "Value" ""
			(at 0 0 0)
			(layer "B.Fab")
			(effects
				(font
					(size 1.27 1.27)
				)
				(justify mirror)
			)
		)
		(duplicate_pad_numbers_are_jumpers no)
		(fp_line
			(start -0.7874 -0.4064)
			(end -0.7874 0.4064)
			(stroke
				(width 0.1524)
				(type default)
			)
			(layer "B.SilkS")
		)
		(fp_line
			(start -0.7874 0.4064)
			(end 0.7874 0.4064)
			(stroke
				(width 0.1524)
				(type default)
			)
			(layer "B.SilkS")
		)
		(fp_line
			(start 0.7874 -0.4064)
			(end -0.7874 -0.4064)
			(stroke
				(width 0.1524)
				(type default)
			)
			(layer "B.SilkS")
		)
		(fp_line
			(start 0.7874 0.4064)
			(end 0.7874 -0.4064)
			(stroke
				(width 0.1524)
				(type default)
			)
			(layer "B.SilkS")
		)
		(fp_line
			(start -0.67945 -0.3048)
			(end -0.67945 0.3048)
			(stroke
				(width 0.1)
				(type default)
			)
			(layer "B.Fab")
		)
		(fp_line
			(start -0.67945 0.3048)
			(end -0.120396 0.3048)
			(stroke
				(width 0.1)
				(type default)
			)
			(layer "B.Fab")
		)
		(fp_line
			(start -0.12065 -0.3048)
			(end -0.67945 -0.3048)
			(stroke
				(width 0.1)
				(type default)
			)
			(layer "B.Fab")
		)
		(fp_line
			(start -0.12065 -0.2794)
			(end -0.12065 -0.3048)
			(stroke
				(width 0.1)
				(type default)
			)
			(layer "B.Fab")
		)
		(fp_line
			(start -0.120396 0.2794)
			(end 0.12065 0.2794)
			(stroke
				(width 0.1)
				(type default)
			)
			(layer "B.Fab")
		)
		(fp_line
			(start -0.120396 0.3048)
			(end -0.120396 0.2794)
			(stroke
				(width 0.1)
				(type default)
			)
			(layer "B.Fab")
		)
		(fp_line
			(start 0.12065 -0.305054)
			(end 0.12065 -0.2794)
			(stroke
				(width 0.1)
				(type default)
			)
			(layer "B.Fab")
		)
		(fp_line
			(start 0.12065 -0.2794)
			(end -0.12065 -0.2794)
			(stroke
				(width 0.1)
				(type default)
			)
			(layer "B.Fab")
		)
		(fp_line
			(start 0.12065 0.2794)
			(end 0.12065 0.3048)
			(stroke
				(width 0.1)
				(type default)
			)
			(layer "B.Fab")
		)
		(fp_line
			(start 0.12065 0.3048)
			(end 0.67945 0.3048)
			(stroke
				(width 0.1)
				(type default)
			)
			(layer "B.Fab")
		)
		(fp_line
			(start 0.67945 -0.305054)
			(end 0.12065 -0.305054)
			(stroke
				(width 0.1)
				(type default)
			)
			(layer "B.Fab")
		)
		(fp_line
			(start 0.67945 0.3048)
			(end 0.67945 -0.305054)
			(stroke
				(width 0.1)
				(type default)
			)
			(layer "B.Fab")
		)
		(pad "1" smd circle
			(at 0.40005 0 180)
			(size 0 0)
			(layers "B.Cu" "B.Mask" "B.Paste")
			(net "PVDDCR_SOC_P0")
		)
		(pad "2" smd circle
			(at -0.40005 0 180)
			(size 0 0)
			(layers "B.Cu" "B.Mask" "B.Paste")
			(net "GND")
		)
	)
	(footprint ""
		(layer "B.Cu")
		(at 84.706206 -386.766562 90)
		(property "Reference" "C306"
			(at 0 0 90)
			(layer "B.SilkS")
			(hide yes)
			(effects
				(font
					(size 1.27 1.27)
				)
				(justify mirror)
			)
		)
		(property "Value" ""
			(at 0 0 90)
			(layer "B.Fab")
			(effects
				(font
					(size 1.27 1.27)
				)
				(justify mirror)
			)
		)
		(duplicate_pad_numbers_are_jumpers no)
		(fp_line
			(start 0.299974 -0.150114)
			(end -0.299974 -0.150114)
			(stroke
				(width 0.1)
				(type default)
			)
			(layer "B.Fab")
		)
		(fp_line
			(start -0.299974 -0.150114)
			(end -0.299974 0.150114)
			(stroke
				(width 0.1)
				(type default)
			)
			(layer "B.Fab")
		)
		(fp_line
			(start 0.299974 0.150114)
			(end 0.299974 -0.150114)
			(stroke
				(width 0.1)
				(type default)
			)
			(layer "B.Fab")
		)
		(fp_line
			(start -0.299974 0.150114)
			(end 0.299974 0.150114)
			(stroke
				(width 0.1)
				(type default)
			)
			(layer "B.Fab")
		)
		(pad "1" smd rect
			(at 0.2667 0 270)
			(size 0.3048 0.381)
			(layers "B.Cu" "B.Mask" "B.Paste")
			(net "P0V9_CPU1_RT1_2A_2D")
		)
		(pad "2" smd rect
			(at -0.2667 0 270)
			(size 0.3048 0.381)
			(layers "B.Cu" "B.Mask" "B.Paste")
			(net "GND")
		)
	)
	(footprint ""
		(layer "B.Cu")
		(at 31.85033 -346.788994 90)
		(property "Reference" "PC627_4"
			(at 0 0 90)
			(layer "B.SilkS")
			(hide yes)
			(effects
				(font
					(size 1.27 1.27)
				)
				(justify mirror)
			)
		)
		(property "Value" ""
			(at 0 0 90)
			(layer "B.Fab")
			(effects
				(font
					(size 1.27 1.27)
				)
				(justify mirror)
			)
		)
		(duplicate_pad_numbers_are_jumpers no)
		(fp_line
			(start 1.524 -0.762)
			(end -1.524 -0.762)
			(stroke
				(width 0.1524)
				(type default)
			)
			(layer "B.SilkS")
		)
		(fp_line
			(start -1.524 -0.762)
			(end -1.524 0.762)
			(stroke
				(width 0.1524)
				(type default)
			)
			(layer "B.SilkS")
		)
		(fp_line
			(start 1.524 0.762)
			(end 1.524 -0.762)
			(stroke
				(width 0.1524)
				(type default)
			)
			(layer "B.SilkS")
		)
		(fp_line
			(start -1.524 0.762)
			(end 1.524 0.762)
			(stroke
				(width 0.1524)
				(type default)
			)
			(layer "B.SilkS")
		)
		(fp_line
			(start 1.1049 -0.724916)
			(end 1.1049 0.724916)
			(stroke
				(width 0.1)
				(type default)
			)
			(layer "B.Fab")
		)
		(fp_line
			(start -1.1049 -0.724916)
			(end 1.1049 -0.724916)
			(stroke
				(width 0.1)
				(type default)
			)
			(layer "B.Fab")
		)
		(fp_line
			(start 1.1049 0.724916)
			(end -1.1049 0.724916)
			(stroke
				(width 0.1)
				(type default)
			)
			(layer "B.Fab")
		)
		(fp_line
			(start -1.1049 0.724916)
			(end -1.1049 -0.724916)
			(stroke
				(width 0.1)
				(type default)
			)
			(layer "B.Fab")
		)
		(pad "1" smd rect
			(at 0.889 0 90)
			(size 1.016 1.27)
			(layers "B.Cu" "B.Mask" "B.Paste")
			(net "SW_P12V_AUX_PVDDIO_P1_FLT")
		)
		(pad "2" smd rect
			(at -0.889 0 90)
			(size 1.016 1.27)
			(layers "B.Cu" "B.Mask" "B.Paste")
			(net "GND")
		)
	)
)
